# BASEBOARD_FAB2 (Tioga Pass) — schematic netlist excerpt (pin names and nets, part order shuffled) for the footprints in the layout excerpt that follows; sources: Cadence DE-HDL packaged netlist, KiCad conversion of Wiwynn_Tioga_Pass_MB.brd

C9N13  CAP  10UF 16V 10% X6S  pkg 0805  page 210 : A = VR_FET_SW_P12V_STBY_PVCCIN_CPU1 ; B = GND
C5P28  CAP  100UF 4V 20% X5R  pkg 0805  page 42 : A = PVCCMCP_CPU0 ; B = GND
R6W7  RES  4.75K 1% EMPTY  pkg 0402  page 247 : A = PCA9555_A2 ; B = GND

(kicad_pcb
	(version 20260206)
	(generator "pcbnew")
	(generator_version "10.0")
	(general
		(thickness 1.6)
		(legacy_teardrops no)
	)
	(paper "A4")
	(title_block
		(title "Wiwynn_Tioga_Pass_MB.brd")
		(comment 1 "Tioga Pass / footprints 4489-4491 of 4770")
	)
	(layers
		(0 "F.Cu" signal "TOP")
		(4 "In1.Cu" signal "L2GND")
		(6 "In2.Cu" signal "L3")
		(8 "In3.Cu" signal "L4GND")
		(10 "In4.Cu" signal "L5")
		(12 "In5.Cu" signal "L6GND")
		(14 "In6.Cu" signal "L7VCC")
		(16 "In7.Cu" signal "L8VCC")
		(18 "In8.Cu" signal "L9GND")
		(20 "In9.Cu" signal "L10")
		(22 "In10.Cu" signal "L11GND")
		(24 "In11.Cu" signal "L12")
		(26 "In12.Cu" signal "L13GND")
		(2 "B.Cu" signal "BOTTOM")
		(9 "F.Adhes" user "F.Adhesive")
		(11 "B.Adhes" user "B.Adhesive")
		(13 "F.Paste" user "Package Geometry/Pastemask Top")
		(15 "B.Paste" user "Package Geometry/Pastemask Bottom")
		(5 "F.SilkS" user "Ref Des/Silkscreen Top")
		(7 "B.SilkS" user "Ref Des/Silkscreen Bottom")
		(1 "F.Mask" user "Board Geometry/Soldermask Top")
		(3 "B.Mask" user "Board Geometry/Soldermask Bottom")
		(17 "Dwgs.User" user "User.Drawings")
		(19 "Cmts.User" user "User.Comments")
		(21 "Eco1.User" user "User.Eco1")
		(23 "Eco2.User" user "User.Eco2")
		(25 "Edge.Cuts" user "Board Geometry/Outline")
		(27 "Margin" user)
		(31 "F.CrtYd" user "Package Geometry/Place Bound Top")
		(29 "B.CrtYd" user "Package Geometry/Place Bound Bottom")
		(35 "F.Fab" user "Ref Des/Assembly Top")
		(33 "B.Fab" user "Ref Des/Assembly Bottom")
	)
	(footprint ""
		(layer "B.Cu")
		(at 32.832802 -97.286064 90)
		(property "Reference" "C9N13"
			(at 0 0 90)
			(layer "B.SilkS")
			(hide yes)
			(effects
				(font
					(size 1.27 1.27)
				)
				(justify mirror)
			)
		)
		(property "Value" ""
			(at 0 0 90)
			(layer "B.Fab")
			(effects
				(font
					(size 1.27 1.27)
				)
				(justify mirror)
			)
		)
		(duplicate_pad_numbers_are_jumpers no)
		(fp_poly
			(pts
				(xy 0.7239 -0.2159) (xy -0.7239 -0.2159) (xy -0.7239 1.9939) (xy 0.7239 1.9939)
			)
			(stroke
				(width 0)
				(type default)
			)
			(fill no)
			(layer "B.CrtYd")
		)
		(fp_line
			(start 0.7239 -0.2159)
			(end 0.7239 1.9939)
			(stroke
				(width 0.1)
				(type default)
			)
			(layer "B.Fab")
		)
		(fp_line
			(start -0.7239 -0.2159)
			(end 0.7239 -0.2159)
			(stroke
				(width 0.1)
				(type default)
			)
			(layer "B.Fab")
		)
		(fp_line
			(start 0.7239 1.9939)
			(end -0.7239 1.9939)
			(stroke
				(width 0.1)
				(type default)
			)
			(layer "B.Fab")
		)
		(fp_line
			(start -0.7239 1.9939)
			(end -0.7239 -0.2159)
			(stroke
				(width 0.1)
				(type default)
			)
			(layer "B.Fab")
		)
		(pad "1" smd rect
			(at 0 0 270)
			(size 1.27 1.016)
			(layers "B.Cu" "B.Mask" "B.Paste")
			(net "VR_FET_SW_P12V_STBY_PVCCIN_CPU1")
		)
		(pad "2" smd rect
			(at 0 1.778 270)
			(size 1.27 1.016)
			(layers "B.Cu" "B.Mask" "B.Paste")
			(net "GND")
		)
		(zone
			(layer "B.Cu")
			(hatch none 0.5)
			(connect_pads
				(clearance 0)
			)
			(min_thickness 0.25)
			(keepout
				(tracks not_allowed)
				(vias allowed)
				(pads allowed)
				(copperpour not_allowed)
				(footprints allowed)
			)
			(placement
				(enabled no)
				(sheetname "")
			)
			(fill
				(thermal_gap 0.5)
				(thermal_bridge_width 0.5)
				(island_removal_mode 0)
			)
			(polygon
				(pts
					(xy 33.340802 -97.921064) (xy 33.340802 -96.651064) (xy 34.102802 -96.651064) (xy 34.102802 -97.921064)
				)
			)
		)
	)
	(footprint ""
		(layer "B.Cu")
		(at 481.623116 -143.247872 90)
		(property "Reference" "R6W7"
			(at 0.8382 -0.67818 90)
			(unlocked yes)
			(layer "B.SilkS")
			(effects
				(font
					(size 0.4064 0.254)
					(thickness 0.1524)
				)
				(justify left mirror)
			)
		)
		(property "Value" ""
			(at 0 0 90)
			(layer "B.Fab")
			(effects
				(font
					(size 1.27 1.27)
				)
				(justify mirror)
			)
		)
		(duplicate_pad_numbers_are_jumpers no)
		(fp_poly
			(pts
				(xy 0.2794 -0.1016) (xy -0.2794 -0.1016) (xy -0.2794 0.9906) (xy 0.2794 0.9906)
			)
			(stroke
				(width 0)
				(type default)
			)
			(fill no)
			(layer "B.CrtYd")
		)
		(fp_line
			(start 0.2794 -0.1016)
			(end 0.2794 0.9906)
			(stroke
				(width 0.1)
				(type default)
			)
			(layer "B.Fab")
		)
		(fp_line
			(start -0.2794 -0.1016)
			(end 0.2794 -0.1016)
			(stroke
				(width 0.1)
				(type default)
			)
			(layer "B.Fab")
		)
		(fp_line
			(start 0.2794 0.9906)
			(end -0.2794 0.9906)
			(stroke
				(width 0.1)
				(type default)
			)
			(layer "B.Fab")
		)
		(fp_line
			(start -0.2794 0.9906)
			(end -0.2794 -0.1016)
			(stroke
				(width 0.1)
				(type default)
			)
			(layer "B.Fab")
		)
		(pad "1" smd rect
			(at 0 0 270)
			(size 0.508 0.508)
			(layers "B.Cu" "B.Mask" "B.Paste")
			(net "PCA9555_A2")
		)
		(pad "2" smd rect
			(at 0 0.889 270)
			(size 0.508 0.508)
			(layers "B.Cu" "B.Mask" "B.Paste")
			(net "GND")
		)
		(zone
			(layer "B.Cu")
			(hatch none 0.5)
			(connect_pads
				(clearance 0)
			)
			(min_thickness 0.25)
			(keepout
				(tracks allowed)
				(vias not_allowed)
				(pads allowed)
				(copperpour not_allowed)
				(footprints allowed)
			)
			(placement
				(enabled no)
				(sheetname "")
			)
			(fill
				(thermal_gap 0.5)
				(thermal_bridge_width 0.5)
				(island_removal_mode 0)
			)
			(polygon
				(pts
					(xy 481.877116 -143.501872) (xy 481.877116 -142.993872) (xy 482.258116 -142.993872) (xy 482.258116 -143.501872)
				)
			)
		)
		(zone
			(layer "B.Cu")
			(hatch none 0.5)
			(connect_pads
				(clearance 0)
			)
			(min_thickness 0.25)
			(keepout
				(tracks not_allowed)
				(vias allowed)
				(pads allowed)
				(copperpour not_allowed)
				(footprints allowed)
			)
			(placement
				(enabled no)
				(sheetname "")
			)
			(fill
				(thermal_gap 0.5)
				(thermal_bridge_width 0.5)
				(island_removal_mode 0)
			)
			(polygon
				(pts
					(xy 482.258116 -143.501872) (xy 482.258116 -142.993872) (xy 481.877116 -142.993872) (xy 481.877116 -143.501872)
				)
			)
		)
	)
	(footprint ""
		(layer "B.Cu")
		(at 275.008086 -73.51014)
		(property "Reference" "C5P28"
			(at 0 0 0)
			(layer "B.SilkS")
			(hide yes)
			(effects
				(font
					(size 1.27 1.27)
				)
				(justify mirror)
			)
		)
		(property "Value" ""
			(at 0 0 0)
			(layer "B.Fab")
			(effects
				(font
					(size 1.27 1.27)
				)
				(justify mirror)
			)
		)
		(duplicate_pad_numbers_are_jumpers no)
		(fp_poly
			(pts
				(xy 0.7239 -0.2159) (xy -0.7239 -0.2159) (xy -0.7239 1.9939) (xy 0.7239 1.9939)
			)
			(stroke
				(width 0)
				(type default)
			)
			(fill no)
			(layer "B.CrtYd")
		)
		(fp_line
			(start -0.7239 -0.2159)
			(end 0.7239 -0.2159)
			(stroke
				(width 0.1)
				(type default)
			)
			(layer "B.Fab")
		)
		(fp_line
			(start -0.7239 1.9939)
			(end -0.7239 -0.2159)
			(stroke
				(width 0.1)
				(type default)
			)
			(layer "B.Fab")
		)
		(fp_line
			(start 0.7239 -0.2159)
			(end 0.7239 1.9939)
			(stroke
				(width 0.1)
				(type default)
			)
			(layer "B.Fab")
		)
		(fp_line
			(start 0.7239 1.9939)
			(end -0.7239 1.9939)
			(stroke
				(width 0.1)
				(type default)
			)
			(layer "B.Fab")
		)
		(pad "1" smd rect
			(at 0 0 180)
			(size 1.27 1.016)
			(layers "B.Cu" "B.Mask" "B.Paste")
			(net "PVCCMCP_CPU0")
		)
		(pad "2" smd rect
			(at 0 1.778 180)
			(size 1.27 1.016)
			(layers "B.Cu" "B.Mask" "B.Paste")
			(net "GND")
		)
		(zone
			(layer "B.Cu")
			(hatch none 0.5)
			(connect_pads
				(clearance 0)
			)
			(min_thickness 0.25)
			(keepout
				(tracks not_allowed)
				(vias allowed)
				(pads allowed)
				(copperpour not_allowed)
				(footprints allowed)
			)
			(placement
				(enabled no)
				(sheetname "")
			)
			(fill
				(thermal_gap 0.5)
				(thermal_bridge_width 0.5)
				(island_removal_mode 0)
			)
			(polygon
				(pts
					(xy 275.643086 -73.00214) (xy 274.373086 -73.00214) (xy 274.373086 -72.24014) (xy 275.643086 -72.24014)
				)
			)
		)
	)
)
